# TIMECARD (Time Appliance Project (Time Card)) — schematic netlist excerpt (pin names and nets, part order shuffled) for the footprints in the layout excerpt that follows; sources: Cadence DE-HDL packaged netlist, KiCad conversion of R4006-B0001-02_R01.brd

C85  CAPACITOR  0.1UF 10V 10%  pkg SMC_0402R_H022  page 23 : \1\ = XP3R3V_FPGA ; \2\ = SG
C17  CAPACITOR  0.1UF 10%  pkg SMC_0402R_H022  page 9 : \1\ = XP3R3V_FPGA ; \2\ = SG

(kicad_pcb
	(version 20260206)
	(generator "pcbnew")
	(generator_version "10.0")
	(general
		(thickness 1.6)
		(legacy_teardrops no)
	)
	(paper "A4")
	(title_block
		(title "timecard-production-celestica-r4006 — R4006-B0001-02_R01.brd")
		(comment 1 "Time Appliance Project (Time Card) / footprints 181-182 of 1113")
	)
	(layers
		(0 "F.Cu" signal "TOP")
		(4 "In1.Cu" signal "L02_GND1")
		(6 "In2.Cu" signal "L03_SIG1")
		(8 "In3.Cu" signal "L04_GND2")
		(10 "In4.Cu" signal "L05_VCC1")
		(12 "In5.Cu" signal "L06_VCC2")
		(14 "In6.Cu" signal "L07_GND3")
		(16 "In7.Cu" signal "L08_SIG2")
		(18 "In8.Cu" signal "L09_GND4")
		(2 "B.Cu" signal "BOTTOM")
		(9 "F.Adhes" user "F.Adhesive")
		(11 "B.Adhes" user "B.Adhesive")
		(13 "F.Paste" user "Package Geometry/Pastemask Top")
		(15 "B.Paste" user "Package Geometry/Pastemask Bottom")
		(5 "F.SilkS" user "Ref Des/Silkscreen Top")
		(7 "B.SilkS" user "Ref Des/Silkscreen Bottom")
		(1 "F.Mask" user "Board Geometry/Soldermask Top")
		(3 "B.Mask" user "Board Geometry/Soldermask Bottom")
		(17 "Dwgs.User" user "User.Drawings")
		(19 "Cmts.User" user "User.Comments")
		(21 "Eco1.User" user "User.Eco1")
		(23 "Eco2.User" user "User.Eco2")
		(25 "Edge.Cuts" user "Board Geometry/Outline")
		(27 "Margin" user)
		(31 "F.CrtYd" user "Package Geometry/Place Bound Top")
		(29 "B.CrtYd" user "Package Geometry/Place Bound Bottom")
		(35 "F.Fab" user "Ref Des/Assembly Top")
		(33 "B.Fab" user "Ref Des/Assembly Bottom")
	)
	(footprint ""
		(layer "F.Cu")
		(at 39.3192 -16.31188 90)
		(property "Reference" "C17"
			(at -3.10388 0.21717 90)
			(unlocked yes)
			(layer "F.SilkS")
			(effects
				(font
					(size 0.7874 0.5842)
					(thickness 0.1524)
				)
			)
		)
		(property "Value" "VAL*"
			(at 0.0762 2.067306 90)
			(unlocked yes)
			(layer "F.Fab")
			(hide yes)
			(effects
				(font
					(size 0.7874 0.5842)
					(thickness 0.1524)
				)
			)
		)
		(property "Tolerance" "TOL*"
			(at 0.0762 3.032506 90)
			(unlocked yes)
			(layer "Cmts.User")
			(hide yes)
			(effects
				(font
					(size 0.7874 0.5842)
					(thickness 0.1524)
				)
			)
		)
		(property "User Part Number" "PARTNUM*"
			(at 0.1016 4.023106 90)
			(unlocked yes)
			(layer "Cmts.User")
			(hide yes)
			(effects
				(font
					(size 0.7874 0.5842)
					(thickness 0.1524)
				)
			)
		)
		(property "Device Type" "CAPACITOR-G105-0B104-CK,0.1UF,A"
			(at 0.0508 1.127506 90)
			(unlocked yes)
			(layer "F.Fab")
			(hide yes)
			(effects
				(font
					(size 0.7874 0.5842)
					(thickness 0.1524)
				)
			)
		)
		(duplicate_pad_numbers_are_jumpers no)
		(fp_line
			(start 1.143 -0.5588)
			(end -1.143 -0.5588)
			(stroke
				(width 0.1)
				(type default)
			)
			(layer "F.SilkS")
		)
		(fp_line
			(start -1.143 -0.5588)
			(end -1.143 0.5588)
			(stroke
				(width 0.1)
				(type default)
			)
			(layer "F.SilkS")
		)
		(fp_line
			(start 1.143 0.5588)
			(end 1.143 -0.5588)
			(stroke
				(width 0.1)
				(type default)
			)
			(layer "F.SilkS")
		)
		(fp_line
			(start -1.143 0.5588)
			(end 1.143 0.5588)
			(stroke
				(width 0.1)
				(type default)
			)
			(layer "F.SilkS")
		)
		(fp_rect
			(start -1.143 -0.5588)
			(end 1.143 0.5588)
			(stroke
				(width 0)
				(type default)
			)
			(fill no)
			(layer "F.CrtYd")
		)
		(fp_line
			(start 0.508 -0.3048)
			(end -0.508 -0.3048)
			(stroke
				(width 0.1)
				(type default)
			)
			(layer "F.Fab")
		)
		(fp_line
			(start -0.508 -0.3048)
			(end -0.508 0.3048)
			(stroke
				(width 0.1)
				(type default)
			)
			(layer "F.Fab")
		)
		(fp_line
			(start 0.508 0.3048)
			(end 0.508 -0.3048)
			(stroke
				(width 0.1)
				(type default)
			)
			(layer "F.Fab")
		)
		(fp_line
			(start -0.508 0.3048)
			(end 0.508 0.3048)
			(stroke
				(width 0.1)
				(type default)
			)
			(layer "F.Fab")
		)
		(pad "1" smd rect
			(at -0.5334 0 90)
			(size 0.7112 0.6096)
			(layers "F.Cu" "F.Mask" "F.Paste")
			(net "XP3R3V_FPGA")
		)
		(pad "2" smd rect
			(at 0.5334 0 90)
			(size 0.7112 0.6096)
			(layers "F.Cu" "F.Mask" "F.Paste")
			(net "SG")
		)
		(zone
			(layer "F.Cu")
			(hatch none 0.5)
			(connect_pads
				(clearance 0)
			)
			(min_thickness 0.25)
			(keepout
				(tracks allowed)
				(vias not_allowed)
				(pads allowed)
				(copperpour not_allowed)
				(footprints allowed)
			)
			(placement
				(enabled no)
				(sheetname "")
			)
			(fill
				(thermal_gap 0.5)
				(thermal_bridge_width 0.5)
				(island_removal_mode 0)
			)
			(polygon
				(pts
					(xy 39.0144 -16.23568) (xy 39.624 -16.23568) (xy 39.624 -16.38808) (xy 39.0144 -16.38808)
				)
			)
		)
	)
	(footprint ""
		(layer "F.Cu")
		(at 16.256 -57.15 -90)
		(property "Reference" "C85"
			(at 2.286 -0.54737 90)
			(unlocked yes)
			(layer "F.SilkS")
			(effects
				(font
					(size 0.7874 0.5842)
					(thickness 0.1524)
				)
			)
		)
		(property "Value" "VAL*"
			(at 0.0762 2.067306 270)
			(unlocked yes)
			(layer "F.Fab")
			(hide yes)
			(effects
				(font
					(size 0.7874 0.5842)
					(thickness 0.1524)
				)
			)
		)
		(property "Device Type" "CAPACITOR-G105-0B104-CK,0.1UF,A"
			(at 0.0508 1.127506 270)
			(unlocked yes)
			(layer "F.Fab")
			(hide yes)
			(effects
				(font
					(size 0.7874 0.5842)
					(thickness 0.1524)
				)
			)
		)
		(property "User Part Number" "PARTNUM*"
			(at 0.1016 4.023106 270)
			(unlocked yes)
			(layer "Cmts.User")
			(hide yes)
			(effects
				(font
					(size 0.7874 0.5842)
					(thickness 0.1524)
				)
			)
		)
		(property "Tolerance" "TOL*"
			(at 0.0762 3.032506 270)
			(unlocked yes)
			(layer "Cmts.User")
			(hide yes)
			(effects
				(font
					(size 0.7874 0.5842)
					(thickness 0.1524)
				)
			)
		)
		(duplicate_pad_numbers_are_jumpers no)
		(fp_line
			(start -1.143 0.5588)
			(end 1.143 0.5588)
			(stroke
				(width 0.1)
				(type default)
			)
			(layer "F.SilkS")
		)
		(fp_line
			(start 1.143 0.5588)
			(end 1.143 -0.5588)
			(stroke
				(width 0.1)
				(type default)
			)
			(layer "F.SilkS")
		)
		(fp_line
			(start -1.143 -0.5588)
			(end -1.143 0.5588)
			(stroke
				(width 0.1)
				(type default)
			)
			(layer "F.SilkS")
		)
		(fp_line
			(start 1.143 -0.5588)
			(end -1.143 -0.5588)
			(stroke
				(width 0.1)
				(type default)
			)
			(layer "F.SilkS")
		)
		(fp_rect
			(start -1.143 -0.5588)
			(end 1.143 0.5588)
			(stroke
				(width 0)
				(type default)
			)
			(fill no)
			(layer "F.CrtYd")
		)
		(fp_line
			(start -0.508 0.3048)
			(end 0.508 0.3048)
			(stroke
				(width 0.1)
				(type default)
			)
			(layer "F.Fab")
		)
		(fp_line
			(start 0.508 0.3048)
			(end 0.508 -0.3048)
			(stroke
				(width 0.1)
				(type default)
			)
			(layer "F.Fab")
		)
		(fp_line
			(start -0.508 -0.3048)
			(end -0.508 0.3048)
			(stroke
				(width 0.1)
				(type default)
			)
			(layer "F.Fab")
		)
		(fp_line
			(start 0.508 -0.3048)
			(end -0.508 -0.3048)
			(stroke
				(width 0.1)
				(type default)
			)
			(layer "F.Fab")
		)
		(pad "1" smd rect
			(at -0.5334 0 270)
			(size 0.7112 0.6096)
			(layers "F.Cu" "F.Mask" "F.Paste")
			(net "XP3R3V_FPGA")
		)
		(pad "2" smd rect
			(at 0.5334 0 270)
			(size 0.7112 0.6096)
			(layers "F.Cu" "F.Mask" "F.Paste")
			(net "SG")
		)
		(zone
			(layer "F.Cu")
			(hatch none 0.5)
			(connect_pads
				(clearance 0)
			)
			(min_thickness 0.25)
			(keepout
				(tracks allowed)
				(vias not_allowed)
				(pads allowed)
				(copperpour not_allowed)
				(footprints allowed)
			)
			(placement
				(enabled no)
				(sheetname "")
			)
			(fill
				(thermal_gap 0.5)
				(thermal_bridge_width 0.5)
				(island_removal_mode 0)
			)
			(polygon
				(pts
					(xy 16.5608 -57.2262) (xy 15.9512 -57.2262) (xy 15.9512 -57.0738) (xy 16.5608 -57.0738)
				)
			)
		)
	)
)
